# T6G (Grand Teton) — schematic netlist excerpt (pin names and nets, part order shuffled) for the footprints in the layout excerpt that follows; sources: Cadence DE-HDL packaged netlist, KiCad conversion of 04192023_DAF0TMB3IC0_F0TG_MB_C_brd_V02_OCP.brd

C2265  Q_CAP  22UF 4V 20% X6S  pkg C0402  page 72 : A = PVDDIO_P1 ; B = GND
C216  Q_CAP  8.2PF 50V 0.1P NP0  pkg C0402  page 28 : A = XTAL_CPU0_X32K_X2 ; B = GND
PC6510  Q_CAP  22UF 4V 20% X6S  pkg C0805  page 360 : A = P1V8_CPU0_RT_1D ; B = GND

(kicad_pcb
	(version 20260206)
	(generator "pcbnew")
	(generator_version "10.0")
	(general
		(thickness 1.6)
		(legacy_teardrops no)
	)
	(paper "A4")
	(title_block
		(title "04192023_DAF0TMB3IC0_F0TG_MB_C_brd_V02_OCP.brd")
		(comment 1 "Grand Teton / footprints 7905-7907 of 8354")
	)
	(layers
		(0 "F.Cu" signal "TOP")
		(4 "In1.Cu" signal "GND")
		(6 "In2.Cu" signal "IN1")
		(8 "In3.Cu" signal "GND1")
		(10 "In4.Cu" signal "IN2")
		(12 "In5.Cu" signal "GND2")
		(14 "In6.Cu" signal "IN3")
		(16 "In7.Cu" signal "GND3")
		(18 "In8.Cu" signal "VCC")
		(20 "In9.Cu" signal "VCC1")
		(22 "In10.Cu" signal "GND4")
		(24 "In11.Cu" signal "IN4")
		(26 "In12.Cu" signal "GND5")
		(28 "In13.Cu" signal "IN5")
		(30 "In14.Cu" signal "GND6")
		(32 "In15.Cu" signal "IN6")
		(34 "In16.Cu" signal "GND7")
		(2 "B.Cu" signal "BOTTOM")
		(9 "F.Adhes" user "F.Adhesive")
		(11 "B.Adhes" user "B.Adhesive")
		(13 "F.Paste" user "Package Geometry/Pastemask Top")
		(15 "B.Paste" user "Package Geometry/Pastemask Bottom")
		(5 "F.SilkS" user "Ref Des/Silkscreen Top")
		(7 "B.SilkS" user "Ref Des/Silkscreen Bottom")
		(1 "F.Mask" user "Board Geometry/Soldermask Top")
		(3 "B.Mask" user "Board Geometry/Soldermask Bottom")
		(17 "Dwgs.User" user "User.Drawings")
		(19 "Cmts.User" user "User.Comments")
		(21 "Eco1.User" user "User.Eco1")
		(23 "Eco2.User" user "User.Eco2")
		(25 "Edge.Cuts" user "Board Geometry/Outline")
		(27 "Margin" user)
		(31 "F.CrtYd" user "Package Geometry/Place Bound Top")
		(29 "B.CrtYd" user "Package Geometry/Place Bound Bottom")
		(35 "F.Fab" user "Ref Des/Assembly Top")
		(33 "B.Fab" user "Ref Des/Assembly Bottom")
	)
	(footprint ""
		(layer "B.Cu")
		(at 402.539962 -314.925964 180)
		(property "Reference" "C216"
			(at 0 0 0)
			(layer "B.SilkS")
			(hide yes)
			(effects
				(font
					(size 1.27 1.27)
				)
				(justify mirror)
			)
		)
		(property "Value" ""
			(at 0 0 0)
			(layer "B.Fab")
			(effects
				(font
					(size 1.27 1.27)
				)
				(justify mirror)
			)
		)
		(duplicate_pad_numbers_are_jumpers no)
		(fp_line
			(start 0.7874 0.4064)
			(end 0.7874 -0.4064)
			(stroke
				(width 0.1524)
				(type default)
			)
			(layer "B.SilkS")
		)
		(fp_line
			(start 0.7874 -0.4064)
			(end -0.7874 -0.4064)
			(stroke
				(width 0.1524)
				(type default)
			)
			(layer "B.SilkS")
		)
		(fp_line
			(start -0.7874 0.4064)
			(end 0.7874 0.4064)
			(stroke
				(width 0.1524)
				(type default)
			)
			(layer "B.SilkS")
		)
		(fp_line
			(start -0.7874 -0.4064)
			(end -0.7874 0.4064)
			(stroke
				(width 0.1524)
				(type default)
			)
			(layer "B.SilkS")
		)
		(fp_line
			(start 0.67945 0.3048)
			(end 0.67945 -0.305054)
			(stroke
				(width 0.1)
				(type default)
			)
			(layer "B.Fab")
		)
		(fp_line
			(start 0.67945 -0.305054)
			(end 0.12065 -0.305054)
			(stroke
				(width 0.1)
				(type default)
			)
			(layer "B.Fab")
		)
		(fp_line
			(start 0.12065 0.3048)
			(end 0.67945 0.3048)
			(stroke
				(width 0.1)
				(type default)
			)
			(layer "B.Fab")
		)
		(fp_line
			(start 0.12065 0.2794)
			(end 0.12065 0.3048)
			(stroke
				(width 0.1)
				(type default)
			)
			(layer "B.Fab")
		)
		(fp_line
			(start 0.12065 -0.2794)
			(end -0.12065 -0.2794)
			(stroke
				(width 0.1)
				(type default)
			)
			(layer "B.Fab")
		)
		(fp_line
			(start 0.12065 -0.305054)
			(end 0.12065 -0.2794)
			(stroke
				(width 0.1)
				(type default)
			)
			(layer "B.Fab")
		)
		(fp_line
			(start -0.120396 0.3048)
			(end -0.120396 0.2794)
			(stroke
				(width 0.1)
				(type default)
			)
			(layer "B.Fab")
		)
		(fp_line
			(start -0.120396 0.2794)
			(end 0.12065 0.2794)
			(stroke
				(width 0.1)
				(type default)
			)
			(layer "B.Fab")
		)
		(fp_line
			(start -0.12065 -0.2794)
			(end -0.12065 -0.3048)
			(stroke
				(width 0.1)
				(type default)
			)
			(layer "B.Fab")
		)
		(fp_line
			(start -0.12065 -0.3048)
			(end -0.67945 -0.3048)
			(stroke
				(width 0.1)
				(type default)
			)
			(layer "B.Fab")
		)
		(fp_line
			(start -0.67945 0.3048)
			(end -0.120396 0.3048)
			(stroke
				(width 0.1)
				(type default)
			)
			(layer "B.Fab")
		)
		(fp_line
			(start -0.67945 -0.3048)
			(end -0.67945 0.3048)
			(stroke
				(width 0.1)
				(type default)
			)
			(layer "B.Fab")
		)
		(pad "1" smd circle
			(at 0.40005 0)
			(size 0 0)
			(layers "B.Cu" "B.Mask" "B.Paste")
			(net "XTAL_CPU0_X32K_X2")
		)
		(pad "2" smd circle
			(at -0.40005 0)
			(size 0 0)
			(layers "B.Cu" "B.Mask" "B.Paste")
			(net "GND")
		)
	)
	(footprint ""
		(layer "B.Cu")
		(at 239.980978 -315.95568 -90)
		(property "Reference" "PC6510"
			(at 0 0 90)
			(layer "B.SilkS")
			(hide yes)
			(effects
				(font
					(size 1.27 1.27)
				)
				(justify mirror)
			)
		)
		(property "Value" ""
			(at 0 0 90)
			(layer "B.Fab")
			(effects
				(font
					(size 1.27 1.27)
				)
				(justify mirror)
			)
		)
		(duplicate_pad_numbers_are_jumpers no)
		(fp_line
			(start -1.524 0.762)
			(end 1.524 0.762)
			(stroke
				(width 0.1524)
				(type default)
			)
			(layer "B.SilkS")
		)
		(fp_line
			(start 1.524 0.762)
			(end 1.524 -0.762)
			(stroke
				(width 0.1524)
				(type default)
			)
			(layer "B.SilkS")
		)
		(fp_line
			(start -1.524 -0.762)
			(end -1.524 0.762)
			(stroke
				(width 0.1524)
				(type default)
			)
			(layer "B.SilkS")
		)
		(fp_line
			(start 1.524 -0.762)
			(end -1.524 -0.762)
			(stroke
				(width 0.1524)
				(type default)
			)
			(layer "B.SilkS")
		)
		(fp_line
			(start -1.1049 0.724916)
			(end -1.1049 -0.724916)
			(stroke
				(width 0.1)
				(type default)
			)
			(layer "B.Fab")
		)
		(fp_line
			(start 1.1049 0.724916)
			(end -1.1049 0.724916)
			(stroke
				(width 0.1)
				(type default)
			)
			(layer "B.Fab")
		)
		(fp_line
			(start -1.1049 -0.724916)
			(end 1.1049 -0.724916)
			(stroke
				(width 0.1)
				(type default)
			)
			(layer "B.Fab")
		)
		(fp_line
			(start 1.1049 -0.724916)
			(end 1.1049 0.724916)
			(stroke
				(width 0.1)
				(type default)
			)
			(layer "B.Fab")
		)
		(pad "1" smd rect
			(at 0.889 0 270)
			(size 1.016 1.27)
			(layers "B.Cu" "B.Mask" "B.Paste")
			(net "P1V8_CPU0_RT_1D")
		)
		(pad "2" smd rect
			(at -0.889 0 270)
			(size 1.016 1.27)
			(layers "B.Cu" "B.Mask" "B.Paste")
			(net "GND")
		)
	)
	(footprint ""
		(layer "B.Cu")
		(at 105.960164 -260.305296 180)
		(property "Reference" "C2265"
			(at 0 0 0)
			(layer "B.SilkS")
			(hide yes)
			(effects
				(font
					(size 1.27 1.27)
				)
				(justify mirror)
			)
		)
		(property "Value" ""
			(at 0 0 0)
			(layer "B.Fab")
			(effects
				(font
					(size 1.27 1.27)
				)
				(justify mirror)
			)
		)
		(duplicate_pad_numbers_are_jumpers no)
		(fp_line
			(start 0.7874 0.4064)
			(end 0.7874 -0.4064)
			(stroke
				(width 0.1524)
				(type default)
			)
			(layer "B.SilkS")
		)
		(fp_line
			(start 0.7874 -0.4064)
			(end -0.7874 -0.4064)
			(stroke
				(width 0.1524)
				(type default)
			)
			(layer "B.SilkS")
		)
		(fp_line
			(start -0.7874 0.4064)
			(end 0.7874 0.4064)
			(stroke
				(width 0.1524)
				(type default)
			)
			(layer "B.SilkS")
		)
		(fp_line
			(start -0.7874 -0.4064)
			(end -0.7874 0.4064)
			(stroke
				(width 0.1524)
				(type default)
			)
			(layer "B.SilkS")
		)
		(fp_line
			(start 0.67945 0.3048)
			(end 0.67945 -0.305054)
			(stroke
				(width 0.1)
				(type default)
			)
			(layer "B.Fab")
		)
		(fp_line
			(start 0.67945 -0.305054)
			(end 0.12065 -0.305054)
			(stroke
				(width 0.1)
				(type default)
			)
			(layer "B.Fab")
		)
		(fp_line
			(start 0.12065 0.3048)
			(end 0.67945 0.3048)
			(stroke
				(width 0.1)
				(type default)
			)
			(layer "B.Fab")
		)
		(fp_line
			(start 0.12065 0.2794)
			(end 0.12065 0.3048)
			(stroke
				(width 0.1)
				(type default)
			)
			(layer "B.Fab")
		)
		(fp_line
			(start 0.12065 -0.2794)
			(end -0.12065 -0.2794)
			(stroke
				(width 0.1)
				(type default)
			)
			(layer "B.Fab")
		)
		(fp_line
			(start 0.12065 -0.305054)
			(end 0.12065 -0.2794)
			(stroke
				(width 0.1)
				(type default)
			)
			(layer "B.Fab")
		)
		(fp_line
			(start -0.120396 0.3048)
			(end -0.120396 0.2794)
			(stroke
				(width 0.1)
				(type default)
			)
			(layer "B.Fab")
		)
		(fp_line
			(start -0.120396 0.2794)
			(end 0.12065 0.2794)
			(stroke
				(width 0.1)
				(type default)
			)
			(layer "B.Fab")
		)
		(fp_line
			(start -0.12065 -0.2794)
			(end -0.12065 -0.3048)
			(stroke
				(width 0.1)
				(type default)
			)
			(layer "B.Fab")
		)
		(fp_line
			(start -0.12065 -0.3048)
			(end -0.67945 -0.3048)
			(stroke
				(width 0.1)
				(type default)
			)
			(layer "B.Fab")
		)
		(fp_line
			(start -0.67945 0.3048)
			(end -0.120396 0.3048)
			(stroke
				(width 0.1)
				(type default)
			)
			(layer "B.Fab")
		)
		(fp_line
			(start -0.67945 -0.3048)
			(end -0.67945 0.3048)
			(stroke
				(width 0.1)
				(type default)
			)
			(layer "B.Fab")
		)
		(pad "1" smd circle
			(at 0.40005 0)
			(size 0 0)
			(layers "B.Cu" "B.Mask" "B.Paste")
			(net "PVDDIO_P1")
		)
		(pad "2" smd circle
			(at -0.40005 0)
			(size 0 0)
			(layers "B.Cu" "B.Mask" "B.Paste")
			(net "GND")
		)
	)
)
